FILE_TYPE = MULTI_PHYS_TABLE;

PART 'TPS2051BDBVT_SOT23_5'
CLASS = IC 

{========================================================================================}
:'CLS_PN'             = 'JEDEC_TYPE'    |'ALT_SYMBOLS'    |'DESCRIPTION'                                       ;
{========================================================================================}
 'G220-10338-01'      = 'SOT23_5'     |'(SOT23_5)'    |'IC,POWER SWITCH,CURRENT-LIMITED,0.5A,SOT-23'  

END_PART

END.

